#ISCELL
  pure_quanta quanta_title_block_c *
  *
#ISCELL
  standard offpage *
  page64_i1
#ISCELL
  standard offpage *
  page64_i100
#ISCELL
  standard offpage *
  page64_i101
#ISCELL
  standard tap *
  page64_i102
#ISCELL
  standard tap *
  page64_i103
#ISCELL
  standard tap *
  page64_i104
#ISCELL
  standard tap *
  page64_i105
#ISCELL
  standard tap *
  page64_i106
#ISCELL
  standard tap *
  page64_i107
#ISCELL
  standard tap *
  page64_i108
#ISCELL
  standard tap *
  page64_i109
#ISCELL
  standard tap *
  page64_i110
#ISCELL
  standard tap *
  page64_i111
#ISCELL
  standard tap *
  page64_i112
#ISCELL
  standard tap *
  page64_i113
#ISCELL
  standard tap *
  page64_i114
#ISCELL
  standard tap *
  page64_i115
#ISCELL
  standard tap *
  page64_i116
#ISCELL
  standard tap *
  page64_i117
#ISCELL
  standard tap *
  page64_i118
#ISCELL
  standard tap *
  page64_i119
#ISCELL
  standard tap *
  page64_i120
#ISCELL
  standard tap *
  page64_i121
#ISCELL
  standard tap *
  page64_i122
#ISCELL
  standard tap *
  page64_i123
#ISCELL
  standard tap *
  page64_i124
#ISCELL
  standard tap *
  page64_i125
#ISCELL
  standard offpage *
  page64_i126
#ISCELL
  standard tap *
  page64_i15
#ISCELL
  standard tap *
  page64_i16
#ISCELL
  standard tap *
  page64_i19
#CELL
  pure_quanta socket4677_azif0045p001c01cs *
  page64_i21
#ISCELL
  standard tap *
  page64_i23
#ISCELL
  standard tap *
  page64_i25
#ISCELL
  standard tap *
  page64_i26
#ISCELL
  standard tap *
  page64_i28
#ISCELL
  standard tap *
  page64_i29
#ISCELL
  standard tap *
  page64_i30
#ISCELL
  standard tap *
  page64_i31
#ISCELL
  standard tap *
  page64_i32
#ISCELL
  standard tap *
  page64_i33
#ISCELL
  standard tap *
  page64_i34
#ISCELL
  standard tap *
  page64_i35
#ISCELL
  standard tap *
  page64_i36
#ISCELL
  standard tap *
  page64_i37
#ISCELL
  standard tap *
  page64_i38
#ISCELL
  standard tap *
  page64_i39
#ISCELL
  standard tap *
  page64_i41
#ISCELL
  standard tap *
  page64_i44
#ISCELL
  standard tap *
  page64_i45
#ISCELL
  standard tap *
  page64_i46
#ISCELL
  standard tap *
  page64_i47
#ISCELL
  standard tap *
  page64_i51
#ISCELL
  standard tap *
  page64_i52
#ISCELL
  standard tap *
  page64_i53
#ISCELL
  standard tap *
  page64_i54
#ISCELL
  standard tap *
  page64_i55
#ISCELL
  standard tap *
  page64_i56
#ISCELL
  standard tap *
  page64_i57
#ISCELL
  standard tap *
  page64_i58
#ISCELL
  standard tap *
  page64_i59
#ISCELL
  standard tap *
  page64_i60
#ISCELL
  standard tap *
  page64_i61
#ISCELL
  standard tap *
  page64_i62
#ISCELL
  standard tap *
  page64_i63
#ISCELL
  standard tap *
  page64_i64
#ISCELL
  standard tap *
  page64_i65
#ISCELL
  standard tap *
  page64_i66
#ISCELL
  standard tap *
  page64_i67
#ISCELL
  standard tap *
  page64_i68
#ISCELL
  standard tap *
  page64_i69
#ISCELL
  standard tap *
  page64_i70
#ISCELL
  standard tap *
  page64_i71
#ISCELL
  standard tap *
  page64_i72
#ISCELL
  standard tap *
  page64_i73
#ISCELL
  standard tap *
  page64_i74
#ISCELL
  standard tap *
  page64_i75
#ISCELL
  standard tap *
  page64_i76
#ISCELL
  standard tap *
  page64_i77
#ISCELL
  standard tap *
  page64_i78
#ISCELL
  standard tap *
  page64_i79
#ISCELL
  standard tap *
  page64_i80
#ISCELL
  standard tap *
  page64_i81
#ISCELL
  standard tap *
  page64_i82
#ISCELL
  standard tap *
  page64_i83
#ISCELL
  standard tap *
  page64_i84
#ISCELL
  standard tap *
  page64_i85
#ISCELL
  standard tap *
  page64_i86
#ISCELL
  standard tap *
  page64_i87
#ISCELL
  standard tap *
  page64_i88
#ISCELL
  standard tap *
  page64_i89
#ISCELL
  standard tap *
  page64_i90
#ISCELL
  standard tap *
  page64_i91
#ISCELL
  standard tap *
  page64_i92
#ISCELL
  standard tap *
  page64_i93
#ISCELL
  standard tap *
  page64_i94
#ISCELL
  standard tap *
  page64_i95
#ISCELL
  standard tap *
  page64_i96
#ISCELL
  standard tap *
  page64_i97
#ISCELL
  standard tap *
  page64_i98
#ISCELL
  standard tap *
  page64_i99
